# S9S_MB_2U (Grand Teton) — schematic netlist excerpt (pin names and nets, part order shuffled) for the footprints in the layout excerpt that follows; sources: Cadence DE-HDL packaged netlist, KiCad conversion of 03242023_DA0F0TMBIJ0_F0T_Motherboard_J_brd_V01_OCP.brd

R4747  Q_RES  33.2 1% CHIP  pkg 0402LF  page 158 : A = OCP_SFF_AUX_PWR_PLD_EN ; B = OCP_SFF_AUX_PWR_PLD_EN_R
PR4525  Q_RES  10M 1% CHIP  pkg 0402LF  page 156 : A = P3V3_OCP_SFF_R ; B = P3V3_OCP_GATE_PU202_1

(kicad_pcb
	(version 20260206)
	(generator "pcbnew")
	(generator_version "10.0")
	(general
		(thickness 1.6)
		(legacy_teardrops no)
	)
	(paper "A4")
	(title_block
		(title "03242023_DA0F0TMBIJ0_F0T_Motherboard_J_brd_V01_OCP.brd")
		(comment 1 "Grand Teton / footprints 2237-2238 of 6105")
	)
	(layers
		(0 "F.Cu" signal "TOP")
		(4 "In1.Cu" signal "GND")
		(6 "In2.Cu" signal "IN1")
		(8 "In3.Cu" signal "GND1")
		(10 "In4.Cu" signal "IN2")
		(12 "In5.Cu" signal "GND2")
		(14 "In6.Cu" signal "IN3")
		(16 "In7.Cu" signal "GND3")
		(18 "In8.Cu" signal "VCC")
		(20 "In9.Cu" signal "VCC1")
		(22 "In10.Cu" signal "GND4")
		(24 "In11.Cu" signal "IN4")
		(26 "In12.Cu" signal "GND5")
		(28 "In13.Cu" signal "IN5")
		(30 "In14.Cu" signal "GND6")
		(32 "In15.Cu" signal "IN6")
		(34 "In16.Cu" signal "GND7")
		(2 "B.Cu" signal "BOTTOM")
		(9 "F.Adhes" user "F.Adhesive")
		(11 "B.Adhes" user "B.Adhesive")
		(13 "F.Paste" user "Package Geometry/Pastemask Top")
		(15 "B.Paste" user "Package Geometry/Pastemask Bottom")
		(5 "F.SilkS" user "Ref Des/Silkscreen Top")
		(7 "B.SilkS" user "Ref Des/Silkscreen Bottom")
		(1 "F.Mask" user "Board Geometry/Soldermask Top")
		(3 "B.Mask" user "Board Geometry/Soldermask Bottom")
		(17 "Dwgs.User" user "User.Drawings")
		(19 "Cmts.User" user "User.Comments")
		(21 "Eco1.User" user "User.Eco1")
		(23 "Eco2.User" user "User.Eco2")
		(25 "Edge.Cuts" user "Board Geometry/Outline")
		(27 "Margin" user)
		(31 "F.CrtYd" user "Package Geometry/Place Bound Top")
		(29 "B.CrtYd" user "Package Geometry/Place Bound Bottom")
		(35 "F.Fab" user "Ref Des/Assembly Top")
		(33 "B.Fab" user "Ref Des/Assembly Bottom")
	)
	(footprint ""
		(layer "F.Cu")
		(at 441.36564 -100.27158 90)
		(property "Reference" "R4747"
			(at 0 0 90)
			(layer "F.SilkS")
			(hide yes)
			(effects
				(font
					(size 1.27 1.27)
				)
			)
		)
		(property "Value" ""
			(at 0 0 90)
			(layer "F.Fab")
			(effects
				(font
					(size 1.27 1.27)
				)
			)
		)
		(duplicate_pad_numbers_are_jumpers no)
		(fp_line
			(start 0.7874 -0.4064)
			(end 0.7874 0.4064)
			(stroke
				(width 0.1524)
				(type default)
			)
			(layer "F.SilkS")
		)
		(fp_line
			(start -0.7874 -0.4064)
			(end 0.7874 -0.4064)
			(stroke
				(width 0.1524)
				(type default)
			)
			(layer "F.SilkS")
		)
		(fp_line
			(start 0.7874 0.4064)
			(end -0.7874 0.4064)
			(stroke
				(width 0.1524)
				(type default)
			)
			(layer "F.SilkS")
		)
		(fp_line
			(start -0.7874 0.4064)
			(end -0.7874 -0.4064)
			(stroke
				(width 0.1524)
				(type default)
			)
			(layer "F.SilkS")
		)
		(fp_line
			(start -0.12065 -0.305054)
			(end -0.12065 -0.2794)
			(stroke
				(width 0.1)
				(type default)
			)
			(layer "F.Fab")
		)
		(fp_line
			(start -0.67945 -0.305054)
			(end -0.12065 -0.305054)
			(stroke
				(width 0.1)
				(type default)
			)
			(layer "F.Fab")
		)
		(fp_line
			(start 0.67945 -0.3048)
			(end 0.67945 0.3048)
			(stroke
				(width 0.1)
				(type default)
			)
			(layer "F.Fab")
		)
		(fp_line
			(start 0.12065 -0.3048)
			(end 0.67945 -0.3048)
			(stroke
				(width 0.1)
				(type default)
			)
			(layer "F.Fab")
		)
		(fp_line
			(start 0.12065 -0.2794)
			(end 0.12065 -0.3048)
			(stroke
				(width 0.1)
				(type default)
			)
			(layer "F.Fab")
		)
		(fp_line
			(start -0.12065 -0.2794)
			(end 0.12065 -0.2794)
			(stroke
				(width 0.1)
				(type default)
			)
			(layer "F.Fab")
		)
		(fp_line
			(start 0.120396 0.2794)
			(end -0.12065 0.2794)
			(stroke
				(width 0.1)
				(type default)
			)
			(layer "F.Fab")
		)
		(fp_line
			(start -0.12065 0.2794)
			(end -0.12065 0.3048)
			(stroke
				(width 0.1)
				(type default)
			)
			(layer "F.Fab")
		)
		(fp_line
			(start 0.67945 0.3048)
			(end 0.120396 0.3048)
			(stroke
				(width 0.1)
				(type default)
			)
			(layer "F.Fab")
		)
		(fp_line
			(start 0.120396 0.3048)
			(end 0.120396 0.2794)
			(stroke
				(width 0.1)
				(type default)
			)
			(layer "F.Fab")
		)
		(fp_line
			(start -0.12065 0.3048)
			(end -0.67945 0.3048)
			(stroke
				(width 0.1)
				(type default)
			)
			(layer "F.Fab")
		)
		(fp_line
			(start -0.67945 0.3048)
			(end -0.67945 -0.305054)
			(stroke
				(width 0.1)
				(type default)
			)
			(layer "F.Fab")
		)
		(pad "1" smd circle
			(at -0.40005 0 90)
			(size 0 0)
			(layers "F.Cu" "F.Mask" "F.Paste")
			(net "OCP_SFF_AUX_PWR_PLD_EN")
		)
		(pad "2" smd circle
			(at 0.40005 0 90)
			(size 0 0)
			(layers "F.Cu" "F.Mask" "F.Paste")
			(net "OCP_SFF_AUX_PWR_PLD_EN_R")
		)
	)
	(footprint ""
		(layer "F.Cu")
		(at 436.608474 -103.768398 90)
		(property "Reference" "PR4525"
			(at 0 0 90)
			(layer "F.SilkS")
			(hide yes)
			(effects
				(font
					(size 1.27 1.27)
				)
			)
		)
		(property "Value" ""
			(at 0 0 90)
			(layer "F.Fab")
			(effects
				(font
					(size 1.27 1.27)
				)
			)
		)
		(duplicate_pad_numbers_are_jumpers no)
		(fp_line
			(start 0.7874 -0.4064)
			(end 0.7874 0.4064)
			(stroke
				(width 0.1524)
				(type default)
			)
			(layer "F.SilkS")
		)
		(fp_line
			(start -0.7874 -0.4064)
			(end 0.7874 -0.4064)
			(stroke
				(width 0.1524)
				(type default)
			)
			(layer "F.SilkS")
		)
		(fp_line
			(start 0.7874 0.4064)
			(end -0.7874 0.4064)
			(stroke
				(width 0.1524)
				(type default)
			)
			(layer "F.SilkS")
		)
		(fp_line
			(start -0.7874 0.4064)
			(end -0.7874 -0.4064)
			(stroke
				(width 0.1524)
				(type default)
			)
			(layer "F.SilkS")
		)
		(fp_line
			(start -0.12065 -0.305054)
			(end -0.12065 -0.2794)
			(stroke
				(width 0.1)
				(type default)
			)
			(layer "F.Fab")
		)
		(fp_line
			(start -0.67945 -0.305054)
			(end -0.12065 -0.305054)
			(stroke
				(width 0.1)
				(type default)
			)
			(layer "F.Fab")
		)
		(fp_line
			(start 0.67945 -0.3048)
			(end 0.67945 0.3048)
			(stroke
				(width 0.1)
				(type default)
			)
			(layer "F.Fab")
		)
		(fp_line
			(start 0.12065 -0.3048)
			(end 0.67945 -0.3048)
			(stroke
				(width 0.1)
				(type default)
			)
			(layer "F.Fab")
		)
		(fp_line
			(start 0.12065 -0.2794)
			(end 0.12065 -0.3048)
			(stroke
				(width 0.1)
				(type default)
			)
			(layer "F.Fab")
		)
		(fp_line
			(start -0.12065 -0.2794)
			(end 0.12065 -0.2794)
			(stroke
				(width 0.1)
				(type default)
			)
			(layer "F.Fab")
		)
		(fp_line
			(start 0.120396 0.2794)
			(end -0.12065 0.2794)
			(stroke
				(width 0.1)
				(type default)
			)
			(layer "F.Fab")
		)
		(fp_line
			(start -0.12065 0.2794)
			(end -0.12065 0.3048)
			(stroke
				(width 0.1)
				(type default)
			)
			(layer "F.Fab")
		)
		(fp_line
			(start 0.67945 0.3048)
			(end 0.120396 0.3048)
			(stroke
				(width 0.1)
				(type default)
			)
			(layer "F.Fab")
		)
		(fp_line
			(start 0.120396 0.3048)
			(end 0.120396 0.2794)
			(stroke
				(width 0.1)
				(type default)
			)
			(layer "F.Fab")
		)
		(fp_line
			(start -0.12065 0.3048)
			(end -0.67945 0.3048)
			(stroke
				(width 0.1)
				(type default)
			)
			(layer "F.Fab")
		)
		(fp_line
			(start -0.67945 0.3048)
			(end -0.67945 -0.305054)
			(stroke
				(width 0.1)
				(type default)
			)
			(layer "F.Fab")
		)
		(pad "1" smd circle
			(at -0.40005 0 90)
			(size 0 0)
			(layers "F.Cu" "F.Mask" "F.Paste")
			(net "P3V3_OCP_SFF_R")
		)
		(pad "2" smd circle
			(at 0.40005 0 90)
			(size 0 0)
			(layers "F.Cu" "F.Mask" "F.Paste")
			(net "P3V3_OCP_GATE_PU202_1")
		)
	)
)
